(kicad_pcb
	(version 20260206)
	(generator "pcbnew")
	(generator_version "10.0")
	(general
		(thickness 1.6)
		(legacy_teardrops no)
	)
	(paper "A4")
	(title_block
		(title "04192023_DAF0TMB3IC0_F0TG_MB_C_brd_V02_OCP.brd")
		(comment 1 "Grand Teton / footprint 1669 of 8354 (U18), pads 1-104 of 484")
	)
	(layers
		(0 "F.Cu" signal "TOP")
		(4 "In1.Cu" signal "GND")
		(6 "In2.Cu" signal "IN1")
		(8 "In3.Cu" signal "GND1")
		(10 "In4.Cu" signal "IN2")
		(12 "In5.Cu" signal "GND2")
		(14 "In6.Cu" signal "IN3")
		(16 "In7.Cu" signal "GND3")
		(18 "In8.Cu" signal "VCC")
		(20 "In9.Cu" signal "VCC1")
		(22 "In10.Cu" signal "GND4")
		(24 "In11.Cu" signal "IN4")
		(26 "In12.Cu" signal "GND5")
		(28 "In13.Cu" signal "IN5")
		(30 "In14.Cu" signal "GND6")
		(32 "In15.Cu" signal "IN6")
		(34 "In16.Cu" signal "GND7")
		(2 "B.Cu" signal "BOTTOM")
		(9 "F.Adhes" user "F.Adhesive")
		(11 "B.Adhes" user "B.Adhesive")
		(13 "F.Paste" user "Package Geometry/Pastemask Top")
		(15 "B.Paste" user "Package Geometry/Pastemask Bottom")
		(5 "F.SilkS" user "Ref Des/Silkscreen Top")
		(7 "B.SilkS" user "Ref Des/Silkscreen Bottom")
		(1 "F.Mask" user "Board Geometry/Soldermask Top")
		(3 "B.Mask" user "Board Geometry/Soldermask Bottom")
		(17 "Dwgs.User" user "User.Drawings")
		(19 "Cmts.User" user "User.Comments")
		(21 "Eco1.User" user "User.Eco1")
		(23 "Eco2.User" user "User.Eco2")
		(25 "Edge.Cuts" user "Board Geometry/Outline")
		(27 "Margin" user)
		(31 "F.CrtYd" user "Package Geometry/Place Bound Top")
		(29 "B.CrtYd" user "Package Geometry/Place Bound Bottom")
		(35 "F.Fab" user "Ref Des/Assembly Top")
		(33 "B.Fab" user "Ref Des/Assembly Bottom")
	)
	(footprint ""
		(layer "F.Cu")
		(at 185.522108 -115.052856 90)
		(property "Reference" "U18"
			(at -10.68451 -12.951206 0)
			(unlocked yes)
			(layer "F.SilkS")
			(effects
				(font
					(size 0.7874 0.5842)
					(thickness 0.1524)
				)
				(justify left)
			)
		)
		(property "Value" ""
			(at 0 0 90)
			(layer "F.Fab")
			(effects
				(font
					(size 1.27 1.27)
				)
			)
		)
		(duplicate_pad_numbers_are_jumpers no)
		(pad "A1" smd circle
			(at -8.400034 -8.400034 90)
			(size 0.4064 0.4064)
			(layers "F.Cu" "F.Mask" "F.Paste")
			(net "GND")
		)
		(pad "A2" smd circle
			(at -7.599934 -8.400034 90)
			(size 0.4064 0.4064)
			(layers "F.Cu" "F.Mask" "F.Paste")
			(net "FM_I3C_CPU1_MUX0_R_SEL")
		)
		(pad "A3" smd circle
			(at -6.800088 -8.400034 90)
			(size 0.4064 0.4064)
			(layers "F.Cu" "F.Mask" "F.Paste")
			(net "SCM_JTAG_MUX_R_S1")
		)
		(pad "A4" smd circle
			(at -5.999988 -8.400034 90)
			(size 0.4064 0.4064)
			(layers "F.Cu" "F.Mask" "F.Paste")
			(net "SGPIO_SCM_DI_R<0>")
		)
		(pad "A5" smd circle
			(at -5.199888 -8.400034 90)
			(size 0.4064 0.4064)
			(layers "F.Cu" "F.Mask" "F.Paste")
			(net "SGPIO_SCM_RESET_N")
		)
		(pad "A6" smd circle
			(at -4.400042 -8.400034 90)
			(size 0.4064 0.4064)
			(layers "F.Cu" "F.Mask" "F.Paste")
			(net "E1S_0_PERST1_CLKREQ_R_N")
		)
		(pad "A7" smd circle
			(at -3.599942 -8.400034 90)
			(size 0.4064 0.4064)
			(layers "F.Cu" "F.Mask" "F.Paste")
			(net "FM_UV_ADR_TRIGGER_R_N")
		)
		(pad "A8" smd circle
			(at -2.800096 -8.400034 90)
			(size 0.4064 0.4064)
			(layers "F.Cu" "F.Mask" "F.Paste")
			(net "SGPIO_OCP_SFF_DATAOUT")
		)
		(pad "A9" smd circle
			(at -1.999996 -8.400034 90)
			(size 0.4064 0.4064)
			(layers "F.Cu" "F.Mask" "F.Paste")
			(net "OCP_V3_1_P3V3_PLD_R_PWRGD")
		)
		(pad "A10" smd circle
			(at -1.199896 -8.400034 90)
			(size 0.4064 0.4064)
			(layers "F.Cu" "F.Mask" "F.Paste")
			(net "OC_ALERT_N")
		)
		(pad "A11" smd circle
			(at -0.40005 -8.400034 90)
			(size 0.4064 0.4064)
			(layers "F.Cu" "F.Mask" "F.Paste")
			(net "FM_BOARD_BMC_SKU_ID4")
		)
		(pad "A12" smd circle
			(at 0.40005 -8.400034 90)
			(size 0.4064 0.4064)
			(layers "F.Cu" "F.Mask" "F.Paste")
			(net "SMB_1_PLD_3V3AUX_SDA_R2")
		)
		(pad "A13" smd circle
			(at 1.199896 -8.400034 90)
			(size 0.4064 0.4064)
			(layers "F.Cu" "F.Mask" "F.Paste")
			(net "SMB_2_PLD_3V3AUX_SCL_R2")
		)
		(pad "A14" smd circle
			(at 1.999996 -8.400034 90)
			(size 0.4064 0.4064)
			(layers "F.Cu" "F.Mask" "F.Paste")
			(net "SGPIO_OCP_V3_2_LD_N")
		)
		(pad "A15" smd circle
			(at 2.800096 -8.400034 90)
			(size 0.4064 0.4064)
			(layers "F.Cu" "F.Mask" "F.Paste")
			(net "SCM_SYS_PWROK")
		)
		(pad "A16" smd circle
			(at 3.599942 -8.400034 90)
			(size 0.4064 0.4064)
			(layers "F.Cu" "F.Mask" "F.Paste")
			(net "PWRGD_P5V")
		)
		(pad "A17" smd circle
			(at 4.400042 -8.400034 90)
			(size 0.4064 0.4064)
			(layers "F.Cu" "F.Mask" "F.Paste")
			(net "PWRGD_PVDDCR_SOC_P1")
		)
		(pad "A18" smd circle
			(at 5.199888 -8.400034 90)
			(size 0.4064 0.4064)
			(layers "F.Cu" "F.Mask" "F.Paste")
			(net "FM_LED_PWRGD_PVDDIO_P1")
		)
		(pad "A19" smd circle
			(at 5.999988 -8.400034 90)
			(size 0.4064 0.4064)
			(layers "F.Cu" "F.Mask" "F.Paste")
			(net "FM_LED_PWRGD_PVDD18_S5_P1")
		)
		(pad "A20" smd circle
			(at 6.800088 -8.400034 90)
			(size 0.4064 0.4064)
			(layers "F.Cu" "F.Mask" "F.Paste")
			(net "P1V8_RETIMER_CPU1_R_EN")
		)
		(pad "A21" smd circle
			(at 7.599934 -8.400034 90)
			(size 0.4064 0.4064)
			(layers "F.Cu" "F.Mask" "F.Paste")
			(net "SMB_BMC_SWB_EN")
		)
		(pad "A22" smd circle
			(at 8.400034 -8.400034 90)
			(size 0.4064 0.4064)
			(layers "F.Cu" "F.Mask" "F.Paste")
			(net "GND")
		)
		(pad "AA1" smd circle
			(at -8.400034 7.599934 90)
			(size 0.4064 0.4064)
			(layers "F.Cu" "F.Mask" "F.Paste")
			(net "OCP_SFF_P3V3_P12V_ADC_ALERT")
		)
		(pad "AA2" smd circle
			(at -7.599934 7.599934 90)
			(size 0.4064 0.4064)
			(layers "F.Cu" "F.Mask" "F.Paste")
			(net "FM_SWB_PWR_EN")
		)
		(pad "AA3" smd circle
			(at -6.800088 7.599934 90)
			(size 0.4064 0.4064)
			(layers "F.Cu" "F.Mask" "F.Paste")
			(net "PRSNT_OCP_SFF_N")
		)
		(pad "AA4" smd circle
			(at -5.999988 7.599934 90)
			(size 0.4064 0.4064)
			(layers "F.Cu" "F.Mask" "F.Paste")
			(net "GPU_FPGA_EROT_RST_R_N")
		)
		(pad "AA5" smd circle
			(at -5.199888 7.599934 90)
			(size 0.4064 0.4064)
			(layers "F.Cu" "F.Mask" "F.Paste")
			(net "GPU_FPGA_EROT_RECOV_R_N")
		)
		(pad "AA6" smd circle
			(at -4.400042 7.599934 90)
			(size 0.4064 0.4064)
			(layers "F.Cu" "F.Mask" "F.Paste")
			(net "PWRGD_PVDD18_S5_R_P1")
		)
		(pad "AA7" smd circle
			(at -3.599942 7.599934 90)
			(size 0.4064 0.4064)
			(layers "F.Cu" "F.Mask" "F.Paste")
			(net "FM_PVDD11_S3_P1_EN")
		)
		(pad "AA8" smd circle
			(at -2.800096 7.599934 90)
			(size 0.4064 0.4064)
			(layers "F.Cu" "F.Mask" "F.Paste")
			(net "FM_PVDD18_S5_P0_EN")
		)
		(pad "AA9" smd circle
			(at -1.999996 7.599934 90)
			(size 0.4064 0.4064)
			(layers "F.Cu" "F.Mask" "F.Paste")
			(net "FM_PVDDIO_P1_EN")
		)
		(pad "AA10" smd circle
			(at -1.199896 7.599934 90)
			(size 0.4064 0.4064)
			(layers "F.Cu" "F.Mask" "F.Paste")
			(net "P0V9_RETIMER_CPU0_EN_R2")
		)
		(pad "AA11" smd circle
			(at -0.40005 7.599934 90)
			(size 0.4064 0.4064)
			(layers "F.Cu" "F.Mask" "F.Paste")
			(net "P12V_E1S_0_EN")
		)
		(pad "AA12" smd circle
			(at 0.40005 7.599934 90)
			(size 0.4064 0.4064)
			(layers "F.Cu" "F.Mask" "F.Paste")
			(net "GPU_3V3IO_RSVD3_ISO_R")
		)
		(pad "AA13" smd circle
			(at 1.199896 7.599934 90)
			(size 0.4064 0.4064)
			(layers "F.Cu" "F.Mask" "F.Paste")
			(net "RST_PERST_E1S_0_R_N")
		)
		(pad "AA14" smd circle
			(at 1.999996 7.599934 90)
			(size 0.4064 0.4064)
			(layers "F.Cu" "F.Mask" "F.Paste")
			(net "PRSNT_CABLE_GPU_A1_ISO_R_N")
		)
		(pad "AA15" smd circle
			(at 2.800096 7.599934 90)
			(size 0.4064 0.4064)
			(layers "F.Cu" "F.Mask" "F.Paste")
			(net "GPU_HMC_PRSNT_ISO_R_N")
		)
		(pad "AA16" smd circle
			(at 3.599942 7.599934 90)
			(size 0.4064 0.4064)
			(layers "F.Cu" "F.Mask" "F.Paste")
			(net "GPU_FPGA_EROT_FATALERR_ISO_R_N")
		)
		(pad "AA17" smd circle
			(at 4.400042 7.599934 90)
			(size 0.4064 0.4064)
			(layers "F.Cu" "F.Mask" "F.Paste")
			(net "FM_SMB_1_ALERT_GPU_ISO_R_N")
		)
		(pad "AA18" smd circle
			(at 5.199888 7.599934 90)
			(size 0.4064 0.4064)
			(layers "F.Cu" "F.Mask" "F.Paste")
			(net "FM_GPU_PWRGD_ISO_R")
		)
		(pad "AA19" smd circle
			(at 5.999988 7.599934 90)
			(size 0.4064 0.4064)
			(layers "F.Cu" "F.Mask" "F.Paste")
			(net "RST_PERST_OCP_V3_2_N")
		)
		(pad "AA20" smd circle
			(at 6.800088 7.599934 90)
			(size 0.4064 0.4064)
			(layers "F.Cu" "F.Mask" "F.Paste")
			(net "P12V_OCP_V3_2_EN_R")
		)
		(pad "AA21" smd circle
			(at 7.599934 7.599934 90)
			(size 0.4064 0.4064)
			(layers "F.Cu" "F.Mask" "F.Paste")
			(net "P0V9_RETIMER_CPU1_EN_R2")
		)
		(pad "AA22" smd circle
			(at 8.400034 7.599934 90)
			(size 0.4064 0.4064)
			(layers "F.Cu" "F.Mask" "F.Paste")
			(net "FM_CPU1_PWRGD_OUT")
		)
		(pad "AB1" smd circle
			(at -8.400034 8.400034 90)
			(size 0.4064 0.4064)
			(layers "F.Cu" "F.Mask" "F.Paste")
			(net "GND")
		)
		(pad "AB2" smd circle
			(at -7.599934 8.400034 90)
			(size 0.4064 0.4064)
			(layers "F.Cu" "F.Mask" "F.Paste")
			(net "GPU_NVS_PWR_BRAKE_R_N")
		)
		(pad "AB3" smd circle
			(at -6.800088 8.400034 90)
			(size 0.4064 0.4064)
			(layers "F.Cu" "F.Mask" "F.Paste")
			(net "PVDDCR_CPU0_P0_PMALERT")
		)
		(pad "AB4" smd circle
			(at -5.999988 8.400034 90)
			(size 0.4064 0.4064)
			(layers "F.Cu" "F.Mask" "F.Paste")
			(net "PRSNT_SWB_ISO_R_N")
		)
		(pad "AB5" smd circle
			(at -5.199888 8.400034 90)
			(size 0.4064 0.4064)
			(layers "F.Cu" "F.Mask" "F.Paste")
			(net "BMC_MONITER")
		)
		(pad "AB6" smd circle
			(at -4.400042 8.400034 90)
			(size 0.4064 0.4064)
			(layers "F.Cu" "F.Mask" "F.Paste")
			(net "FM_PWRGD_PVDD33_S5")
		)
		(pad "AB7" smd circle
			(at -3.599942 8.400034 90)
			(size 0.4064 0.4064)
			(layers "F.Cu" "F.Mask" "F.Paste")
			(net "FM_PWRGD_PVDD11_S3_P1")
		)
		(pad "AB8" smd circle
			(at -2.800096 8.400034 90)
			(size 0.4064 0.4064)
			(layers "F.Cu" "F.Mask" "F.Paste")
			(net "FM_PWRGD_PVDD18_S5_P0")
		)
		(pad "AB9" smd circle
			(at -1.999996 8.400034 90)
			(size 0.4064 0.4064)
			(layers "F.Cu" "F.Mask" "F.Paste")
			(net "FM_PWRGD_PVDDIO_P1")
		)
		(pad "AB10" smd circle
			(at -1.199896 8.400034 90)
			(size 0.4064 0.4064)
			(layers "F.Cu" "F.Mask" "F.Paste")
			(net "BMC_FPGA_LED1")
		)
		(pad "AB11" smd circle
			(at -0.40005 8.400034 90)
			(size 0.4064 0.4064)
			(layers "F.Cu" "F.Mask" "F.Paste")
			(net "FM_LED_PWRGD_PVDD18_S5_P0")
		)
		(pad "AB12" smd circle
			(at 0.40005 8.400034 90)
			(size 0.4064 0.4064)
			(layers "F.Cu" "F.Mask" "F.Paste")
			(net "GPU_3V3IO_RSVD1_ISO_R")
		)
		(pad "AB13" smd circle
			(at 1.199896 8.400034 90)
			(size 0.4064 0.4064)
			(layers "F.Cu" "F.Mask" "F.Paste")
			(net "FM_RST_PERST_SCM_R_N")
		)
		(pad "AB14" smd circle
			(at 1.999996 8.400034 90)
			(size 0.4064 0.4064)
			(layers "F.Cu" "F.Mask" "F.Paste")
			(net "GPU_3V3IO_RSVD5_FFU_ISO_R")
		)
		(pad "AB15" smd circle
			(at 2.800096 8.400034 90)
			(size 0.4064 0.4064)
			(layers "F.Cu" "F.Mask" "F.Paste")
			(net "GPU_BASE_HMC_READY_ISO_R")
		)
		(pad "AB16" smd circle
			(at 3.599942 8.400034 90)
			(size 0.4064 0.4064)
			(layers "F.Cu" "F.Mask" "F.Paste")
			(net "GPU_PRSNT_N_ISO_R")
		)
		(pad "AB17" smd circle
			(at 4.400042 8.400034 90)
			(size 0.4064 0.4064)
			(layers "F.Cu" "F.Mask" "F.Paste")
			(net "FM_SWB_BIC_READY_ISO_R_N")
		)
		(pad "AB18" smd circle
			(at 5.199888 8.400034 90)
			(size 0.4064 0.4064)
			(layers "F.Cu" "F.Mask" "F.Paste")
			(net "FM_SWB_PWRGD_ISO_R")
		)
		(pad "AB19" smd circle
			(at 5.999988 8.400034 90)
			(size 0.4064 0.4064)
			(layers "F.Cu" "F.Mask" "F.Paste")
			(net "GPU_FPGA_READY_ISO_R")
		)
		(pad "AB20" smd circle
			(at 6.800088 8.400034 90)
			(size 0.4064 0.4064)
			(layers "F.Cu" "F.Mask" "F.Paste")
			(net "PRSNT_HDT_N")
		)
		(pad "AB21" smd circle
			(at 7.599934 8.400034 90)
			(size 0.4064 0.4064)
			(layers "F.Cu" "F.Mask" "F.Paste")
			(net "PU_SPI_PLD_CS_N")
		)
		(pad "AB22" smd circle
			(at 8.400034 8.400034 90)
			(size 0.4064 0.4064)
			(layers "F.Cu" "F.Mask" "F.Paste")
			(net "GND")
		)
		(pad "B1" smd circle
			(at -8.400034 -7.599934 90)
			(size 0.4064 0.4064)
			(layers "F.Cu" "F.Mask" "F.Paste")
			(net "FM_I3C_CPU0_MUX0_OE_R_N")
		)
		(pad "B2" smd circle
			(at -7.599934 -7.599934 90)
			(size 0.4064 0.4064)
			(layers "F.Cu" "F.Mask" "F.Paste")
			(net "FM_I3C_CPU1_MUX0_OE_R_N")
		)
		(pad "B3" smd circle
			(at -6.800088 -7.599934 90)
			(size 0.4064 0.4064)
			(layers "F.Cu" "F.Mask" "F.Paste")
			(net "SCM_JTAG_MUX_R_S0")
		)
		(pad "B4" smd circle
			(at -5.999988 -7.599934 90)
			(size 0.4064 0.4064)
			(layers "F.Cu" "F.Mask" "F.Paste")
			(net "SGPIO_SCM_DO_<1>")
		)
		(pad "B5" smd circle
			(at -5.199888 -7.599934 90)
			(size 0.4064 0.4064)
			(layers "F.Cu" "F.Mask" "F.Paste")
			(net "SGPIO_SCM_LD_<1>")
		)
		(pad "B6" smd circle
			(at -4.400042 -7.599934 90)
			(size 0.4064 0.4064)
			(layers "F.Cu" "F.Mask" "F.Paste")
			(net "IRQ_HSC_FAULT_BUF_R_N")
		)
		(pad "B7" smd circle
			(at -3.599942 -7.599934 90)
			(size 0.4064 0.4064)
			(layers "F.Cu" "F.Mask" "F.Paste")
			(net "GND")
		)
		(pad "B8" smd circle
			(at -2.800096 -7.599934 90)
			(size 0.4064 0.4064)
			(layers "F.Cu" "F.Mask" "F.Paste")
			(net "SGPIO_OCP_SFF_DATAIN")
		)
		(pad "B9" smd circle
			(at -1.999996 -7.599934 90)
			(size 0.4064 0.4064)
			(layers "F.Cu" "F.Mask" "F.Paste")
			(net "P3V3_OCP_SFF_EN")
		)
		(pad "B10" smd circle
			(at -1.199896 -7.599934 90)
			(size 0.4064 0.4064)
			(layers "F.Cu" "F.Mask" "F.Paste")
			(net "UV_ALERT_N")
		)
		(pad "B11" smd circle
			(at -0.40005 -7.599934 90)
			(size 0.4064 0.4064)
			(layers "F.Cu" "F.Mask" "F.Paste")
			(net "FM_BOARD_BMC_SKU_ID3")
		)
		(pad "B12" smd circle
			(at 0.40005 -7.599934 90)
			(size 0.4064 0.4064)
			(layers "F.Cu" "F.Mask" "F.Paste")
			(net "SMB_1_PLD_3V3AUX_SCL_R2")
		)
		(pad "B13" smd circle
			(at 1.199896 -7.599934 90)
			(size 0.4064 0.4064)
			(layers "F.Cu" "F.Mask" "F.Paste")
			(net "SMB_2_PLD_3V3AUX_SDA_R2")
		)
		(pad "B14" smd circle
			(at 1.999996 -7.599934 90)
			(size 0.4064 0.4064)
			(layers "F.Cu" "F.Mask" "F.Paste")
			(net "SGPIO_OCP_V3_2_DATAIN")
		)
		(pad "B15" smd circle
			(at 2.800096 -7.599934 90)
			(size 0.4064 0.4064)
			(layers "F.Cu" "F.Mask" "F.Paste")
			(net "P1V8_RETIMER_CPU0_R_EN")
		)
		(pad "B16" smd circle
			(at 3.599942 -7.599934 90)
			(size 0.4064 0.4064)
			(layers "F.Cu" "F.Mask" "F.Paste")
			(net "GND")
		)
		(pad "B17" smd circle
			(at 4.400042 -7.599934 90)
			(size 0.4064 0.4064)
			(layers "F.Cu" "F.Mask" "F.Paste")
			(net "PVDDCR_CPU0_P0_EN")
		)
		(pad "B18" smd circle
			(at 5.199888 -7.599934 90)
			(size 0.4064 0.4064)
			(layers "F.Cu" "F.Mask" "F.Paste")
			(net "FM_LED_PWRGD_PVDDCR_SOC_P1")
		)
		(pad "B19" smd circle
			(at 5.999988 -7.599934 90)
			(size 0.4064 0.4064)
			(layers "F.Cu" "F.Mask" "F.Paste")
			(net "FM_LED_PWRGD_PVDD11_S3_P1")
		)
		(pad "B20" smd circle
			(at 6.800088 -7.599934 90)
			(size 0.4064 0.4064)
			(layers "F.Cu" "F.Mask" "F.Paste")
			(net "FM_SOL_UART_CH_SEL")
		)
		(pad "B21" smd circle
			(at 7.599934 -7.599934 90)
			(size 0.4064 0.4064)
			(layers "F.Cu" "F.Mask" "F.Paste")
			(net "IRQ_SML1_PMBUS_ALERT_N")
		)
		(pad "B22" smd circle
			(at 8.400034 -7.599934 90)
			(size 0.4064 0.4064)
			(layers "F.Cu" "F.Mask" "F.Paste")
			(net "FM_OCP_V3_2_PWR_GOOD")
		)
		(pad "C1" smd circle
			(at -8.400034 -6.800088 90)
			(size 0.4064 0.4064)
			(layers "F.Cu" "F.Mask" "F.Paste")
			(net "FM_CPU0_XTRIG_L5")
		)
		(pad "C2" smd circle
			(at -7.599934 -6.800088 90)
			(size 0.4064 0.4064)
			(layers "F.Cu" "F.Mask" "F.Paste")
			(net "GND")
		)
		(pad "C3" smd circle
			(at -6.800088 -6.800088 90)
			(size 0.4064 0.4064)
			(layers "F.Cu" "F.Mask" "F.Paste")
			(net "FM_I3C_CPU0_MUX0_R_SEL")
		)
		(pad "C4" smd circle
			(at -5.999988 -6.800088 90)
			(size 0.4064 0.4064)
			(layers "F.Cu" "F.Mask" "F.Paste")
			(net "FM_I3C_CPU0_MUX1_OE_R_N")
		)
		(pad "C5" smd circle
			(at -5.199888 -6.800088 90)
			(size 0.4064 0.4064)
			(layers "F.Cu" "F.Mask" "F.Paste")
			(net "FM_BOARD_BMC_SKU_ID0")
		)
		(pad "C6" smd circle
			(at -4.400042 -6.800088 90)
			(size 0.4064 0.4064)
			(layers "F.Cu" "F.Mask" "F.Paste")
			(net "SGPIO_SCM_DI_R<1>")
		)
		(pad "C7" smd circle
			(at -3.599942 -6.800088 90)
			(size 0.4064 0.4064)
			(layers "F.Cu" "F.Mask" "F.Paste")
			(net "P3V3_AUX")
		)
		(pad "C8" smd circle
			(at -2.800096 -6.800088 90)
			(size 0.4064 0.4064)
			(layers "F.Cu" "F.Mask" "F.Paste")
			(net "PCIE_M2_SSD0_PRSNT_N")
		)
		(pad "C9" smd circle
			(at -1.999996 -6.800088 90)
			(size 0.4064 0.4064)
			(layers "F.Cu" "F.Mask" "F.Paste")
			(net "SGPIO_OCP_SFF_CLK")
		)
		(pad "C10" smd circle
			(at -1.199896 -6.800088 90)
			(size 0.4064 0.4064)
			(layers "F.Cu" "F.Mask" "F.Paste")
			(net "JTAG_SCM_PLD_TMS")
		)
		(pad "C11" smd circle
			(at -0.40005 -6.800088 90)
			(size 0.4064 0.4064)
			(layers "F.Cu" "F.Mask" "F.Paste")
			(net "GND")
		)
		(pad "C12" smd circle
			(at 0.40005 -6.800088 90)
			(size 0.4064 0.4064)
			(layers "F.Cu" "F.Mask" "F.Paste")
			(net "P3V3_AUX")
		)
		(pad "C13" smd circle
			(at 1.199896 -6.800088 90)
			(size 0.4064 0.4064)
			(layers "F.Cu" "F.Mask" "F.Paste")
			(net "SCM_ROT_CPU_RST_R_N")
		)
		(pad "C14" smd circle
			(at 1.999996 -6.800088 90)
			(size 0.4064 0.4064)
			(layers "F.Cu" "F.Mask" "F.Paste")
			(net "SGPIO_OCP_V3_2_DATAOUT")
		)
		(pad "C15" smd circle
			(at 2.800096 -6.800088 90)
			(size 0.4064 0.4064)
			(layers "F.Cu" "F.Mask" "F.Paste")
			(net "PVDDCR_SOC_P1_EN")
		)
		(pad "C16" smd circle
			(at 3.599942 -6.800088 90)
			(size 0.4064 0.4064)
			(layers "F.Cu" "F.Mask" "F.Paste")
			(net "P3V3_AUX")
		)
	)
)
